# SCM (Grand Teton) — schematic netlist excerpt (pin names and nets, part order shuffled) for the footprints in the layout excerpt that follows; sources: Cadence DE-HDL packaged netlist, KiCad conversion of 12092022_DA0F0TMDCD0_F0T_Management_Board_D_brd_V3_OCP.brd

R873  Q_RES  0 5% EMPTY  pkg 0402LF  page 53 : A = PWRGD_P2V5_AUX_R3 ; B = PWRGD_P2V5_AUX
R430  Q_RES  4.7K 1% CHIP  pkg 0402LF  page 27 : A = P3V3_AUX ; B = FM_BMC_ONCTL_R_N

(kicad_pcb
	(version 20260206)
	(generator "pcbnew")
	(generator_version "10.0")
	(general
		(thickness 1.6)
		(legacy_teardrops no)
	)
	(paper "A4")
	(title_block
		(title "12092022_DA0F0TMDCD0_F0T_Management_Board_D_brd_V3_OCP.brd")
		(comment 1 "Grand Teton / footprints 755-756 of 1440")
	)
	(layers
		(0 "F.Cu" signal "TOP")
		(4 "In1.Cu" signal "GND")
		(6 "In2.Cu" signal "IN1")
		(8 "In3.Cu" signal "GND1")
		(10 "In4.Cu" signal "IN2")
		(12 "In5.Cu" signal "VCC")
		(14 "In6.Cu" signal "VCC1")
		(16 "In7.Cu" signal "IN3")
		(18 "In8.Cu" signal "GND2")
		(20 "In9.Cu" signal "IN4")
		(22 "In10.Cu" signal "GND3")
		(2 "B.Cu" signal "BOTTOM")
		(9 "F.Adhes" user "F.Adhesive")
		(11 "B.Adhes" user "B.Adhesive")
		(13 "F.Paste" user "Package Geometry/Pastemask Top")
		(15 "B.Paste" user "Package Geometry/Pastemask Bottom")
		(5 "F.SilkS" user "Ref Des/Silkscreen Top")
		(7 "B.SilkS" user "Ref Des/Silkscreen Bottom")
		(1 "F.Mask" user "Board Geometry/Soldermask Top")
		(3 "B.Mask" user "Board Geometry/Soldermask Bottom")
		(17 "Dwgs.User" user "User.Drawings")
		(19 "Cmts.User" user "User.Comments")
		(21 "Eco1.User" user "User.Eco1")
		(23 "Eco2.User" user "User.Eco2")
		(25 "Edge.Cuts" user "Board Geometry/Outline")
		(27 "Margin" user)
		(31 "F.CrtYd" user "Package Geometry/Place Bound Top")
		(29 "B.CrtYd" user "Package Geometry/Place Bound Bottom")
		(35 "F.Fab" user "Ref Des/Assembly Top")
		(33 "B.Fab" user "Ref Des/Assembly Bottom")
	)
	(footprint ""
		(layer "B.Cu")
		(at 39.414958 -82.836512 180)
		(property "Reference" "R430"
			(at 0 0 0)
			(layer "B.SilkS")
			(hide yes)
			(effects
				(font
					(size 1.27 1.27)
				)
				(justify mirror)
			)
		)
		(property "Value" ""
			(at 0 0 0)
			(layer "B.Fab")
			(effects
				(font
					(size 1.27 1.27)
				)
				(justify mirror)
			)
		)
		(duplicate_pad_numbers_are_jumpers no)
		(fp_line
			(start 0.7874 0.4064)
			(end 0.7874 -0.4064)
			(stroke
				(width 0.1524)
				(type default)
			)
			(layer "B.SilkS")
		)
		(fp_line
			(start 0.7874 -0.4064)
			(end -0.7874 -0.4064)
			(stroke
				(width 0.1524)
				(type default)
			)
			(layer "B.SilkS")
		)
		(fp_line
			(start -0.7874 0.4064)
			(end 0.7874 0.4064)
			(stroke
				(width 0.1524)
				(type default)
			)
			(layer "B.SilkS")
		)
		(fp_line
			(start -0.7874 -0.4064)
			(end -0.7874 0.4064)
			(stroke
				(width 0.1524)
				(type default)
			)
			(layer "B.SilkS")
		)
		(fp_line
			(start 0.67945 0.3048)
			(end 0.67945 -0.305054)
			(stroke
				(width 0.1)
				(type default)
			)
			(layer "B.Fab")
		)
		(fp_line
			(start 0.67945 -0.305054)
			(end 0.12065 -0.305054)
			(stroke
				(width 0.1)
				(type default)
			)
			(layer "B.Fab")
		)
		(fp_line
			(start 0.12065 0.3048)
			(end 0.67945 0.3048)
			(stroke
				(width 0.1)
				(type default)
			)
			(layer "B.Fab")
		)
		(fp_line
			(start 0.12065 0.2794)
			(end 0.12065 0.3048)
			(stroke
				(width 0.1)
				(type default)
			)
			(layer "B.Fab")
		)
		(fp_line
			(start 0.12065 -0.2794)
			(end -0.12065 -0.2794)
			(stroke
				(width 0.1)
				(type default)
			)
			(layer "B.Fab")
		)
		(fp_line
			(start 0.12065 -0.305054)
			(end 0.12065 -0.2794)
			(stroke
				(width 0.1)
				(type default)
			)
			(layer "B.Fab")
		)
		(fp_line
			(start -0.120396 0.3048)
			(end -0.120396 0.2794)
			(stroke
				(width 0.1)
				(type default)
			)
			(layer "B.Fab")
		)
		(fp_line
			(start -0.120396 0.2794)
			(end 0.12065 0.2794)
			(stroke
				(width 0.1)
				(type default)
			)
			(layer "B.Fab")
		)
		(fp_line
			(start -0.12065 -0.2794)
			(end -0.12065 -0.3048)
			(stroke
				(width 0.1)
				(type default)
			)
			(layer "B.Fab")
		)
		(fp_line
			(start -0.12065 -0.3048)
			(end -0.67945 -0.3048)
			(stroke
				(width 0.1)
				(type default)
			)
			(layer "B.Fab")
		)
		(fp_line
			(start -0.67945 0.3048)
			(end -0.120396 0.3048)
			(stroke
				(width 0.1)
				(type default)
			)
			(layer "B.Fab")
		)
		(fp_line
			(start -0.67945 -0.3048)
			(end -0.67945 0.3048)
			(stroke
				(width 0.1)
				(type default)
			)
			(layer "B.Fab")
		)
		(pad "1" smd circle
			(at 0.40005 0)
			(size 0 0)
			(layers "B.Cu" "B.Mask" "B.Paste")
			(net "P3V3_AUX")
		)
		(pad "2" smd circle
			(at -0.40005 0)
			(size 0 0)
			(layers "B.Cu" "B.Mask" "B.Paste")
			(net "FM_BMC_ONCTL_R_N")
		)
	)
	(footprint ""
		(layer "B.Cu")
		(at 78.7908 -33.4645 -90)
		(property "Reference" "R873"
			(at 0 0 90)
			(layer "B.SilkS")
			(hide yes)
			(effects
				(font
					(size 1.27 1.27)
				)
				(justify mirror)
			)
		)
		(property "Value" ""
			(at 0 0 90)
			(layer "B.Fab")
			(effects
				(font
					(size 1.27 1.27)
				)
				(justify mirror)
			)
		)
		(duplicate_pad_numbers_are_jumpers no)
		(fp_line
			(start -0.7874 0.4064)
			(end 0.7874 0.4064)
			(stroke
				(width 0.1524)
				(type default)
			)
			(layer "B.SilkS")
		)
		(fp_line
			(start 0.7874 0.4064)
			(end 0.7874 -0.4064)
			(stroke
				(width 0.1524)
				(type default)
			)
			(layer "B.SilkS")
		)
		(fp_line
			(start -0.7874 -0.4064)
			(end -0.7874 0.4064)
			(stroke
				(width 0.1524)
				(type default)
			)
			(layer "B.SilkS")
		)
		(fp_line
			(start 0.7874 -0.4064)
			(end -0.7874 -0.4064)
			(stroke
				(width 0.1524)
				(type default)
			)
			(layer "B.SilkS")
		)
		(fp_line
			(start -0.67945 0.3048)
			(end -0.120396 0.3048)
			(stroke
				(width 0.1)
				(type default)
			)
			(layer "B.Fab")
		)
		(fp_line
			(start -0.120396 0.3048)
			(end -0.120396 0.2794)
			(stroke
				(width 0.1)
				(type default)
			)
			(layer "B.Fab")
		)
		(fp_line
			(start 0.12065 0.3048)
			(end 0.67945 0.3048)
			(stroke
				(width 0.1)
				(type default)
			)
			(layer "B.Fab")
		)
		(fp_line
			(start 0.67945 0.3048)
			(end 0.67945 -0.305054)
			(stroke
				(width 0.1)
				(type default)
			)
			(layer "B.Fab")
		)
		(fp_line
			(start -0.120396 0.2794)
			(end 0.12065 0.2794)
			(stroke
				(width 0.1)
				(type default)
			)
			(layer "B.Fab")
		)
		(fp_line
			(start 0.12065 0.2794)
			(end 0.12065 0.3048)
			(stroke
				(width 0.1)
				(type default)
			)
			(layer "B.Fab")
		)
		(fp_line
			(start -0.12065 -0.2794)
			(end -0.12065 -0.3048)
			(stroke
				(width 0.1)
				(type default)
			)
			(layer "B.Fab")
		)
		(fp_line
			(start 0.12065 -0.2794)
			(end -0.12065 -0.2794)
			(stroke
				(width 0.1)
				(type default)
			)
			(layer "B.Fab")
		)
		(fp_line
			(start -0.67945 -0.3048)
			(end -0.67945 0.3048)
			(stroke
				(width 0.1)
				(type default)
			)
			(layer "B.Fab")
		)
		(fp_line
			(start -0.12065 -0.3048)
			(end -0.67945 -0.3048)
			(stroke
				(width 0.1)
				(type default)
			)
			(layer "B.Fab")
		)
		(fp_line
			(start 0.12065 -0.305054)
			(end 0.12065 -0.2794)
			(stroke
				(width 0.1)
				(type default)
			)
			(layer "B.Fab")
		)
		(fp_line
			(start 0.67945 -0.305054)
			(end 0.12065 -0.305054)
			(stroke
				(width 0.1)
				(type default)
			)
			(layer "B.Fab")
		)
		(pad "1" smd circle
			(at 0.40005 0 90)
			(size 0 0)
			(layers "B.Cu" "B.Mask" "B.Paste")
			(net "PWRGD_P2V5_AUX_R3")
		)
		(pad "2" smd circle
			(at -0.40005 0 90)
			(size 0 0)
			(layers "B.Cu" "B.Mask" "B.Paste")
			(net "PWRGD_P2V5_AUX")
		)
	)
)
